# S9S_MB_2U (Grand Teton) — schematic netlist excerpt (pin names and nets, part order shuffled) for the footprints in the layout excerpt that follows; sources: Cadence DE-HDL packaged netlist, KiCad conversion of 03242023_DA0F0TMBIJ0_F0T_Motherboard_J_brd_V01_OCP.brd

R679  Q_RES  499 1% CHIP  pkg 0402LF  page 229 : A = PVNN_TERM_CPU0 ; B = I3C_SPD_DDRABCD_CPU0_SCL
C1899  Q_CAP  0.01UF 50V 10% X7R  pkg C0402  page 217 : A = P3V3_AUX_FPGA_VCCIO4 ; B = GND

(kicad_pcb
	(version 20260206)
	(generator "pcbnew")
	(generator_version "10.0")
	(general
		(thickness 1.6)
		(legacy_teardrops no)
	)
	(paper "A4")
	(title_block
		(title "03242023_DA0F0TMBIJ0_F0T_Motherboard_J_brd_V01_OCP.brd")
		(comment 1 "Grand Teton / footprints 5442-5443 of 6105")
	)
	(layers
		(0 "F.Cu" signal "TOP")
		(4 "In1.Cu" signal "GND")
		(6 "In2.Cu" signal "IN1")
		(8 "In3.Cu" signal "GND1")
		(10 "In4.Cu" signal "IN2")
		(12 "In5.Cu" signal "GND2")
		(14 "In6.Cu" signal "IN3")
		(16 "In7.Cu" signal "GND3")
		(18 "In8.Cu" signal "VCC")
		(20 "In9.Cu" signal "VCC1")
		(22 "In10.Cu" signal "GND4")
		(24 "In11.Cu" signal "IN4")
		(26 "In12.Cu" signal "GND5")
		(28 "In13.Cu" signal "IN5")
		(30 "In14.Cu" signal "GND6")
		(32 "In15.Cu" signal "IN6")
		(34 "In16.Cu" signal "GND7")
		(2 "B.Cu" signal "BOTTOM")
		(9 "F.Adhes" user "F.Adhesive")
		(11 "B.Adhes" user "B.Adhesive")
		(13 "F.Paste" user "Package Geometry/Pastemask Top")
		(15 "B.Paste" user "Package Geometry/Pastemask Bottom")
		(5 "F.SilkS" user "Ref Des/Silkscreen Top")
		(7 "B.SilkS" user "Ref Des/Silkscreen Bottom")
		(1 "F.Mask" user "Board Geometry/Soldermask Top")
		(3 "B.Mask" user "Board Geometry/Soldermask Bottom")
		(17 "Dwgs.User" user "User.Drawings")
		(19 "Cmts.User" user "User.Comments")
		(21 "Eco1.User" user "User.Eco1")
		(23 "Eco2.User" user "User.Eco2")
		(25 "Edge.Cuts" user "Board Geometry/Outline")
		(27 "Margin" user)
		(31 "F.CrtYd" user "Package Geometry/Place Bound Top")
		(29 "B.CrtYd" user "Package Geometry/Place Bound Bottom")
		(35 "F.Fab" user "Ref Des/Assembly Top")
		(33 "B.Fab" user "Ref Des/Assembly Bottom")
	)
	(footprint ""
		(layer "B.Cu")
		(at 179.9082 -106.76255 -90)
		(property "Reference" "C1899"
			(at 0 0 90)
			(layer "B.SilkS")
			(hide yes)
			(effects
				(font
					(size 1.27 1.27)
				)
				(justify mirror)
			)
		)
		(property "Value" ""
			(at 0 0 90)
			(layer "B.Fab")
			(effects
				(font
					(size 1.27 1.27)
				)
				(justify mirror)
			)
		)
		(duplicate_pad_numbers_are_jumpers no)
		(fp_line
			(start -0.69215 0.2921)
			(end 0.69215 0.2921)
			(stroke
				(width 0.1524)
				(type default)
			)
			(layer "B.SilkS")
		)
		(fp_line
			(start 0.69215 0.2921)
			(end 0.69215 -0.2921)
			(stroke
				(width 0.1524)
				(type default)
			)
			(layer "B.SilkS")
		)
		(fp_line
			(start -0.69215 -0.2921)
			(end -0.69215 0.2921)
			(stroke
				(width 0.1524)
				(type default)
			)
			(layer "B.SilkS")
		)
		(fp_line
			(start 0.69215 -0.2921)
			(end -0.69215 -0.2921)
			(stroke
				(width 0.1524)
				(type default)
			)
			(layer "B.SilkS")
		)
		(fp_line
			(start -0.51435 0.2794)
			(end 0.51435 0.2794)
			(stroke
				(width 0.1)
				(type default)
			)
			(layer "B.Fab")
		)
		(fp_line
			(start 0.51435 0.2794)
			(end 0.51435 -0.2794)
			(stroke
				(width 0.1)
				(type default)
			)
			(layer "B.Fab")
		)
		(fp_line
			(start -0.51435 -0.2794)
			(end -0.51435 0.2794)
			(stroke
				(width 0.1)
				(type default)
			)
			(layer "B.Fab")
		)
		(fp_line
			(start 0.51435 -0.2794)
			(end -0.51435 -0.2794)
			(stroke
				(width 0.1)
				(type default)
			)
			(layer "B.Fab")
		)
		(pad "1" smd circle
			(at 0.40005 0 90)
			(size 0 0)
			(layers "B.Cu" "B.Mask" "B.Paste")
			(net "P3V3_AUX_FPGA_VCCIO4")
		)
		(pad "2" smd circle
			(at -0.40005 0 90)
			(size 0 0)
			(layers "B.Cu" "B.Mask" "B.Paste")
			(net "GND")
		)
		(zone
			(layer "B.Cu")
			(hatch none 0.5)
			(connect_pads
				(clearance 0)
			)
			(min_thickness 0.25)
			(keepout
				(tracks not_allowed)
				(vias allowed)
				(pads allowed)
				(copperpour not_allowed)
				(footprints allowed)
			)
			(placement
				(enabled no)
				(sheetname "")
			)
			(fill
				(thermal_gap 0.5)
				(thermal_bridge_width 0.5)
				(island_removal_mode 0)
			)
			(polygon
				(pts
					(xy 179.82057 -106.57205) (xy 179.762404 -106.66349) (xy 179.762404 -106.86288) (xy 179.82057 -106.95305)
					(xy 179.99583 -106.95305) (xy 180.05425 -106.86288) (xy 180.05425 -106.66349) (xy 179.996084 -106.57205)
				)
			)
		)
	)
	(footprint ""
		(layer "B.Cu")
		(at 336.494882 -188.393578)
		(property "Reference" "R679"
			(at 0 0 0)
			(layer "B.SilkS")
			(hide yes)
			(effects
				(font
					(size 1.27 1.27)
				)
				(justify mirror)
			)
		)
		(property "Value" ""
			(at 0 0 0)
			(layer "B.Fab")
			(effects
				(font
					(size 1.27 1.27)
				)
				(justify mirror)
			)
		)
		(duplicate_pad_numbers_are_jumpers no)
		(fp_line
			(start -0.7874 -0.4064)
			(end -0.7874 0.4064)
			(stroke
				(width 0.1524)
				(type default)
			)
			(layer "B.SilkS")
		)
		(fp_line
			(start -0.7874 0.4064)
			(end 0.7874 0.4064)
			(stroke
				(width 0.1524)
				(type default)
			)
			(layer "B.SilkS")
		)
		(fp_line
			(start 0.7874 -0.4064)
			(end -0.7874 -0.4064)
			(stroke
				(width 0.1524)
				(type default)
			)
			(layer "B.SilkS")
		)
		(fp_line
			(start 0.7874 0.4064)
			(end 0.7874 -0.4064)
			(stroke
				(width 0.1524)
				(type default)
			)
			(layer "B.SilkS")
		)
		(fp_line
			(start -0.67945 -0.3048)
			(end -0.67945 0.3048)
			(stroke
				(width 0.1)
				(type default)
			)
			(layer "B.Fab")
		)
		(fp_line
			(start -0.67945 0.3048)
			(end -0.120396 0.3048)
			(stroke
				(width 0.1)
				(type default)
			)
			(layer "B.Fab")
		)
		(fp_line
			(start -0.12065 -0.3048)
			(end -0.67945 -0.3048)
			(stroke
				(width 0.1)
				(type default)
			)
			(layer "B.Fab")
		)
		(fp_line
			(start -0.12065 -0.2794)
			(end -0.12065 -0.3048)
			(stroke
				(width 0.1)
				(type default)
			)
			(layer "B.Fab")
		)
		(fp_line
			(start -0.120396 0.2794)
			(end 0.12065 0.2794)
			(stroke
				(width 0.1)
				(type default)
			)
			(layer "B.Fab")
		)
		(fp_line
			(start -0.120396 0.3048)
			(end -0.120396 0.2794)
			(stroke
				(width 0.1)
				(type default)
			)
			(layer "B.Fab")
		)
		(fp_line
			(start 0.12065 -0.305054)
			(end 0.12065 -0.2794)
			(stroke
				(width 0.1)
				(type default)
			)
			(layer "B.Fab")
		)
		(fp_line
			(start 0.12065 -0.2794)
			(end -0.12065 -0.2794)
			(stroke
				(width 0.1)
				(type default)
			)
			(layer "B.Fab")
		)
		(fp_line
			(start 0.12065 0.2794)
			(end 0.12065 0.3048)
			(stroke
				(width 0.1)
				(type default)
			)
			(layer "B.Fab")
		)
		(fp_line
			(start 0.12065 0.3048)
			(end 0.67945 0.3048)
			(stroke
				(width 0.1)
				(type default)
			)
			(layer "B.Fab")
		)
		(fp_line
			(start 0.67945 -0.305054)
			(end 0.12065 -0.305054)
			(stroke
				(width 0.1)
				(type default)
			)
			(layer "B.Fab")
		)
		(fp_line
			(start 0.67945 0.3048)
			(end 0.67945 -0.305054)
			(stroke
				(width 0.1)
				(type default)
			)
			(layer "B.Fab")
		)
		(pad "1" smd circle
			(at 0.40005 0 180)
			(size 0 0)
			(layers "B.Cu" "B.Mask" "B.Paste")
			(net "PVNN_TERM_CPU0")
		)
		(pad "2" smd circle
			(at -0.40005 0 180)
			(size 0 0)
			(layers "B.Cu" "B.Mask" "B.Paste")
			(net "I3C_SPD_DDRABCD_CPU0_SCL")
		)
	)
)
